FILE_TYPE = MACRO_DRAWING;
SET COLOR_WIRE YELLOW;
SET COLOR_PROP MONO;
SET COLOR_DOT WHITE;
SET COLOR_ARC YELLOW;
SET COLOR_BODY GREEN;
SET COLOR_NOTE MONO;
SET PROP_DISPLAY VALUE;
SET PAGE_NUMBER P166;
FORCEADD RES..1
(-4550 3125);
FORCEPROP 1 LAST WATTAGE 1/16W
J 2
(-4575 2975);
DISPLAY 0.617021 (-4575 2975);
PAINT SKYBLUE (-4575 2975);
FORCEPROP 1 LAST PART_NUMBER G21497-005
J 0
(-4750 3025);
DISPLAY 0.617021 (-4750 3025);
PAINT BLUE (-4750 3025);
FORCEPROP 1 LAST PACK_TYPE 0402
J 0
(-4350 2975);
DISPLAY 0.617021 (-4350 2975);
PAINT SKYBLUE (-4350 2975);
FORCEPROP 1 LAST MATERIAL EMPTY
J 0
(-4550 2975);
DISPLAY 0.617021 (-4550 2975);
PAINT RED (-4550 2975);
FORCEPROP 1 LASTPIN (-4650 3125) $PN 1
J 0
(-4638 3137);
DISPLAY 0.617021 (-4638 3137);
PAINT MONO (-4638 3137);
FORCEPROP 1 LAST VALUE 0.0
J 2
(-4600 3075);
DISPLAY 0.617021 (-4600 3075);
PAINT SKYBLUE (-4600 3075);
FORCEPROP 1 LASTPIN (-4450 3125) $PN 2
J 0
(-4488 3137);
DISPLAY 0.617021 (-4488 3137);
PAINT MONO (-4488 3137);
FORCEPROP 1 LAST LOCATION R7C18
J 0
(-4600 3175);
DISPLAY 0.617021 (-4600 3175);
PAINT AQUA (-4600 3175);
FORCEPROP 1 LAST TOLERANCE 5%
J 0
(-4475 3075);
DISPLAY 0.617021 (-4475 3075);
PAINT SKYBLUE (-4475 3075);
FORCEPROP 2 LAST CDS_LIB mstr_discrete
J 0
(-4550 3125);
DISPLAY 1.531915 (-4550 3125);
PAINT ORANGE (-4550 3125);
DISPLAY INVISIBLE (-4550 3125);
FORCEPROP 2 LAST CDS_LOCATION R7C18
J 0
(-4600 3175);
DISPLAY 0.617021 (-4600 3175);
PAINT AQUA (-4600 3175);
DISPLAY INVISIBLE (-4600 3175);
FORCEPROP 2 LAST ROOM PECI
J 0
(-4600 3225);
DISPLAY 1.021277 (-4600 3225);
PAINT ORANGE (-4600 3225);
DISPLAY INVISIBLE (-4600 3225);
FORCEPROP 2 LAST BOM_COST DEBUG
J 0
(-4600 3275);
DISPLAY 1.021277 (-4600 3275);
PAINT ORANGE (-4600 3275);
DISPLAY INVISIBLE (-4600 3275);
FORCEPROP 1 LAST PATH I11
J 0
(-4600 3275);
DISPLAY 1.319149 (-4600 3275);
PAINT GREEN (-4600 3275);
DISPLAY INVISIBLE (-4600 3275);
FORCEPROP 2 LAST SEC 1
J 0
(-4600 3350);
DISPLAY 0.680851 (-4600 3350);
PAINT MONO (-4600 3350);
DISPLAY INVISIBLE (-4600 3350);
FORCEPROP 2 LAST SEC_TYPE 0402
J 0
(-4600 3350);
DISPLAY 1.021277 (-4600 3350);
PAINT ORANGE (-4600 3350);
DISPLAY INVISIBLE (-4600 3350);
FORCEADD RES..2
(-4850 3500);
FORCEPROP 1 LAST PACK_TYPE 0402
J 0
(-4810 3325);
DISPLAY 0.617021 (-4810 3325);
PAINT SKYBLUE (-4810 3325);
FORCEPROP 1 LASTPIN (-4850 3400) $PN 2
J 0
(-4845 3410);
DISPLAY 0.617021 (-4845 3410);
PAINT MONO (-4845 3410);
FORCEPROP 1 LAST TOLERANCE 1%
J 0
(-4805 3525);
DISPLAY 0.617021 (-4805 3525);
PAINT SKYBLUE (-4805 3525);
FORCEPROP 1 LAST WATTAGE 1/16W
J 0
(-4810 3475);
DISPLAY 0.617021 (-4810 3475);
PAINT SKYBLUE (-4810 3475);
FORCEPROP 1 LAST MATERIAL EMPTY
J 0
(-4810 3425);
DISPLAY 0.617021 (-4810 3425);
PAINT RED (-4810 3425);
FORCEPROP 1 LASTPIN (-4850 3600) $PN 1
J 0
(-4845 3562);
DISPLAY 0.617021 (-4845 3562);
PAINT MONO (-4845 3562);
FORCEPROP 1 LAST VALUE 4.75K
J 0
(-4805 3575);
DISPLAY 0.617021 (-4805 3575);
PAINT SKYBLUE (-4805 3575);
FORCEPROP 1 LAST LOCATION R7C22
J 0
(-4805 3625);
DISPLAY 0.617021 (-4805 3625);
PAINT AQUA (-4805 3625);
FORCEPROP 1 LAST PART_NUMBER G21796-072
J 0
(-4810 3375);
DISPLAY 0.617021 (-4810 3375);
PAINT BLUE (-4810 3375);
FORCEPROP 2 LAST CDS_LIB mstr_discrete
J 0
(-4850 3500);
DISPLAY 1.531915 (-4850 3500);
PAINT ORANGE (-4850 3500);
DISPLAY INVISIBLE (-4850 3500);
FORCEPROP 2 LAST CDS_LOCATION R7C22
J 0
(-4805 3625);
DISPLAY 0.617021 (-4805 3625);
PAINT AQUA (-4805 3625);
DISPLAY INVISIBLE (-4805 3625);
FORCEPROP 1 LAST PATH I14
J 0
(-4800 3675);
DISPLAY 1.319149 (-4800 3675);
PAINT GREEN (-4800 3675);
DISPLAY INVISIBLE (-4800 3675);
FORCEPROP 2 LAST ROOM PECI
J 0
(-4800 3675);
DISPLAY 1.021277 (-4800 3675);
PAINT ORANGE (-4800 3675);
DISPLAY INVISIBLE (-4800 3675);
FORCEPROP 2 LAST SEC 1
J 0
(-4800 3750);
DISPLAY 0.680851 (-4800 3750);
PAINT MONO (-4800 3750);
DISPLAY INVISIBLE (-4800 3750);
FORCEPROP 2 LAST BOM_COST DEBUG
J 0
(-4800 3725);
DISPLAY 1.021277 (-4800 3725);
PAINT ORANGE (-4800 3725);
DISPLAY INVISIBLE (-4800 3725);
FORCEPROP 2 LAST SEC_TYPE 0402
J 0
(-4800 3750);
DISPLAY 1.021277 (-4800 3750);
PAINT ORANGE (-4800 3750);
DISPLAY INVISIBLE (-4800 3750);
FORCEADD RES..1
(-4675 2525);
FORCEPROP 1 LAST VALUE 0.0
J 2
(-4725 2475);
DISPLAY 0.617021 (-4725 2475);
PAINT SKYBLUE (-4725 2475);
FORCEPROP 1 LAST WATTAGE 1/16W
J 2
(-4700 2375);
DISPLAY 0.617021 (-4700 2375);
PAINT SKYBLUE (-4700 2375);
FORCEPROP 1 LASTPIN (-4775 2525) $PN 1
J 0
(-4763 2537);
DISPLAY 0.617021 (-4763 2537);
PAINT MONO (-4763 2537);
FORCEPROP 1 LASTPIN (-4575 2525) $PN 2
J 0
(-4613 2537);
DISPLAY 0.617021 (-4613 2537);
PAINT MONO (-4613 2537);
FORCEPROP 1 LAST MATERIAL CHIP
J 0
(-4675 2375);
DISPLAY 0.617021 (-4675 2375);
PAINT SKYBLUE (-4675 2375);
FORCEPROP 1 LAST PACK_TYPE 0402
J 0
(-4700 2325);
DISPLAY 0.617021 (-4700 2325);
PAINT SKYBLUE (-4700 2325);
FORCEPROP 1 LAST PART_NUMBER G21497-005
J 0
(-4875 2425);
DISPLAY 0.617021 (-4875 2425);
PAINT BLUE (-4875 2425);
FORCEPROP 1 LAST LOCATION R7C19
J 0
(-4725 2575);
DISPLAY 0.617021 (-4725 2575);
PAINT AQUA (-4725 2575);
FORCEPROP 1 LAST TOLERANCE 5%
J 0
(-4600 2475);
DISPLAY 0.617021 (-4600 2475);
PAINT SKYBLUE (-4600 2475);
FORCEPROP 2 LAST CDS_LIB mstr_discrete
J 0
(-4675 2525);
DISPLAY 1.531915 (-4675 2525);
PAINT ORANGE (-4675 2525);
DISPLAY INVISIBLE (-4675 2525);
FORCEPROP 2 LAST CDS_LOCATION R7C19
J 0
(-4725 2575);
DISPLAY 0.617021 (-4725 2575);
PAINT AQUA (-4725 2575);
DISPLAY INVISIBLE (-4725 2575);
FORCEPROP 1 LAST PATH I15
J 0
(-4725 2675);
DISPLAY 1.319149 (-4725 2675);
PAINT GREEN (-4725 2675);
DISPLAY INVISIBLE (-4725 2675);
FORCEPROP 2 LAST ROOM PECI
J 0
(-4725 2625);
DISPLAY 1.021277 (-4725 2625);
PAINT ORANGE (-4725 2625);
DISPLAY INVISIBLE (-4725 2625);
FORCEPROP 2 LAST SEC_TYPE 0402
J 0
(-4725 2750);
DISPLAY 1.021277 (-4725 2750);
PAINT ORANGE (-4725 2750);
DISPLAY INVISIBLE (-4725 2750);
FORCEPROP 2 LAST BOM_COST DEBUG
J 0
(-4725 2675);
DISPLAY 1.021277 (-4725 2675);
PAINT ORANGE (-4725 2675);
DISPLAY INVISIBLE (-4725 2675);
FORCEPROP 2 LAST SEC 1
J 0
(-4725 2750);
DISPLAY 0.680851 (-4725 2750);
PAINT MONO (-4725 2750);
DISPLAY INVISIBLE (-4725 2750);
FORCEADD OFFPAGE..3
R 2
(-5750 3125);
FORCEPROP 2 LAST $XR0 145 
J 0
(-6060 3125);
DISPLAY 0.638298 (-6060 3125);
PAINT MONO (-6060 3125);
FORCEPROP 1 LAST COMMENT_BODY TRUE
J 2
(-5700 3025);
DISPLAY 0.978723 (-5700 3025);
PAINT GREEN (-5700 3025);
DISPLAY INVISIBLE (-5700 3025);
FORCEPROP 1 LAST OFFPAGE TRUE
J 2
(-6075 3000);
PAINT GREEN (-6075 3000);
DISPLAY INVISIBLE (-6075 3000);
FORCEPROP 2 LAST PATH I16
J 0
(-5690 3200);
DISPLAY 1.361702 (-5690 3200);
PAINT ORANGE (-5690 3200);
DISPLAY INVISIBLE (-5690 3200);
FORCEPROP 2 LAST CDS_LIB mstr_standard
J 0
(-5750 3125);
DISPLAY 1.531915 (-5750 3125);
PAINT ORANGE (-5750 3125);
DISPLAY INVISIBLE (-5750 3125);
FORCEADD OFFPAGE..3
R 2
(-5750 2525);
FORCEPROP 2 LAST $XR0 118 
J 0
(-6060 2525);
DISPLAY 0.638298 (-6060 2525);
PAINT MONO (-6060 2525);
FORCEPROP 1 LAST OFFPAGE TRUE
J 2
(-6075 2400);
PAINT GREEN (-6075 2400);
DISPLAY INVISIBLE (-6075 2400);
FORCEPROP 1 LAST COMMENT_BODY TRUE
J 2
(-5700 2425);
DISPLAY 0.978723 (-5700 2425);
PAINT GREEN (-5700 2425);
DISPLAY INVISIBLE (-5700 2425);
FORCEPROP 2 LAST CDS_LIB mstr_standard
J 0
(-5750 2525);
DISPLAY 1.531915 (-5750 2525);
PAINT ORANGE (-5750 2525);
DISPLAY INVISIBLE (-5750 2525);
FORCEPROP 2 LAST PATH I17
J 0
(-5690 2600);
DISPLAY 1.361702 (-5690 2600);
PAINT ORANGE (-5690 2600);
DISPLAY INVISIBLE (-5690 2600);
FORCEADD OFFPAGE..6
(-5750 1400);
FORCEPROP 2 LAST $XR0 21 
J 0
(-6029 1400);
DISPLAY 0.638298 (-6029 1400);
PAINT MONO (-6029 1400);
FORCEPROP 2 LAST $XR1 55 
J 0
(-6119 1400);
DISPLAY 0.638298 (-6119 1400);
PAINT MONO (-6119 1400);
FORCEPROP 1 LAST COMMENT_BODY TRUE
J 0
(-5650 1325);
DISPLAY 1.170213 (-5650 1325);
PAINT GREEN (-5650 1325);
DISPLAY INVISIBLE (-5650 1325);
FORCEPROP 2 LAST CDS_LIB mstr_standard
J 0
(-5750 1400);
DISPLAY 1.531915 (-5750 1400);
PAINT ORANGE (-5750 1400);
DISPLAY INVISIBLE (-5750 1400);
FORCEPROP 2 LAST PATH I2
J 0
(-5550 1475);
DISPLAY 1.361702 (-5550 1475);
PAINT ORANGE (-5550 1475);
DISPLAY INVISIBLE (-5550 1475);
FORCEPROP 1 LAST OFFPAGE TRUE
J 0
(-5425 1275);
PAINT GREEN (-5425 1275);
DISPLAY INVISIBLE (-5425 1275);
FORCEADD RES..2
R 2
(-5050 3500);
FORCEPROP 1 LAST WATTAGE 1/16W
J 2
(-5090 3475);
DISPLAY 0.617021 (-5090 3475);
PAINT SKYBLUE (-5090 3475);
FORCEPROP 1 LAST MATERIAL CHIP
J 2
(-5090 3425);
DISPLAY 0.617021 (-5090 3425);
PAINT SKYBLUE (-5090 3425);
FORCEPROP 1 LAST PACK_TYPE 0402
J 2
(-5090 3325);
DISPLAY 0.617021 (-5090 3325);
PAINT SKYBLUE (-5090 3325);
FORCEPROP 1 LAST TOLERANCE 1%
J 2
(-5095 3525);
DISPLAY 0.617021 (-5095 3525);
PAINT SKYBLUE (-5095 3525);
FORCEPROP 1 LAST VALUE 4.75K
J 2
(-5095 3575);
DISPLAY 0.617021 (-5095 3575);
PAINT SKYBLUE (-5095 3575);
FORCEPROP 1 LAST PART_NUMBER G21796-072
J 2
(-5090 3375);
DISPLAY 0.617021 (-5090 3375);
PAINT BLUE (-5090 3375);
FORCEPROP 1 LAST LOCATION R7C17
J 2
(-5095 3625);
DISPLAY 0.617021 (-5095 3625);
PAINT AQUA (-5095 3625);
FORCEPROP 1 LASTPIN (-5050 3400) $PN 2
J 2
(-5055 3410);
DISPLAY 0.617021 (-5055 3410);
PAINT MONO (-5055 3410);
FORCEPROP 1 LASTPIN (-5050 3600) $PN 1
J 2
(-5055 3562);
DISPLAY 0.617021 (-5055 3562);
PAINT MONO (-5055 3562);
FORCEPROP 2 LAST CDS_LIB mstr_discrete
J 2
(-5050 3500);
DISPLAY 1.531915 (-5050 3500);
PAINT ORANGE (-5050 3500);
DISPLAY INVISIBLE (-5050 3500);
FORCEPROP 2 LAST ROOM PECI
J 0
(-5075 3675);
DISPLAY 1.021277 (-5075 3675);
PAINT ORANGE (-5075 3675);
DISPLAY INVISIBLE (-5075 3675);
FORCEPROP 1 LAST PATH I28
J 2
(-5100 3675);
DISPLAY 1.319149 (-5100 3675);
PAINT GREEN (-5100 3675);
DISPLAY INVISIBLE (-5100 3675);
FORCEPROP 2 LAST CDS_LOCATION R7C17
J 2
(-5095 3625);
DISPLAY 0.617021 (-5095 3625);
PAINT AQUA (-5095 3625);
DISPLAY INVISIBLE (-5095 3625);
FORCEPROP 2 LAST SEC 1
J 0
(-5100 3725);
DISPLAY 0.936170 (-5100 3725);
PAINT MONO (-5100 3725);
DISPLAY INVISIBLE (-5100 3725);
FORCEPROP 2 LAST SEC_TYPE 0402
J 0
(-5100 3725);
PAINT MONO (-5100 3725);
DISPLAY INVISIBLE (-5100 3725);
FORCEPROP 2 LAST BOM_COST DEBUG
J 0
(-5075 3725);
DISPLAY 1.021277 (-5075 3725);
PAINT ORANGE (-5075 3725);
DISPLAY INVISIBLE (-5075 3725);
FORCEADD PVCCIO_CPU0..1
(-4850 3775);
FORCEPROP 3 LASTPIN (-4850 3725) SIG_NAME PVCCIO_CPU0\g
J 0
(-4840 3735);
DISPLAY 0.659574 (-4840 3735);
PAINT MONO (-4840 3735);
DISPLAY INVISIBLE (-4840 3735);
FORCEPROP 1 LAST VOLTAGE 1.1V
J 0
(-4895 3732);
DISPLAY 0.340426 (-4895 3732);
PAINT SKYBLUE (-4895 3732);
DISPLAY INVISIBLE (-4895 3732);
FORCEPROP 1 LAST BODY_TYPE PLUMBING
J 0
(-4895 3732);
DISPLAY 0.340426 (-4895 3732);
PAINT GREEN (-4895 3732);
DISPLAY INVISIBLE (-4895 3732);
FORCEPROP 2 LAST CDS_LIB mstr_symbols
J 0
(-4850 3775);
PAINT ORANGE (-4850 3775);
DISPLAY INVISIBLE (-4850 3775);
FORCEPROP 1 LAST PATH I31
J 0
(-4800 3800);
DISPLAY 0.872340 (-4800 3800);
PAINT AQUA (-4800 3800);
DISPLAY INVISIBLE (-4800 3800);
FORCEPROP 1 LAST HDL_POWER PVCCIO_CPU0
J 1
(-4850 3825);
DISPLAY 0.872340 (-4850 3825);
PAINT GREEN (-4850 3825);
DISPLAY INVISIBLE (-4850 3825);
FORCEADD RES..2
(-4475 2200);
FORCEPROP 1 LAST PACK_TYPE 0402
J 0
(-4435 2025);
DISPLAY 0.617021 (-4435 2025);
PAINT SKYBLUE (-4435 2025);
FORCEPROP 1 LAST TOLERANCE 1%
J 0
(-4430 2225);
DISPLAY 0.617021 (-4430 2225);
PAINT SKYBLUE (-4430 2225);
FORCEPROP 1 LASTPIN (-4475 2100) $PN 2
J 0
(-4470 2110);
DISPLAY 0.617021 (-4470 2110);
PAINT ORANGE (-4470 2110);
FORCEPROP 1 LASTPIN (-4475 2300) $PN 1
J 0
(-4470 2262);
DISPLAY 0.617021 (-4470 2262);
PAINT ORANGE (-4470 2262);
FORCEPROP 1 LAST WATTAGE 1/16W
J 0
(-4435 2175);
DISPLAY 0.617021 (-4435 2175);
PAINT SKYBLUE (-4435 2175);
FORCEPROP 1 LAST MATERIAL CHIP
J 0
(-4435 2125);
DISPLAY 0.617021 (-4435 2125);
PAINT SKYBLUE (-4435 2125);
FORCEPROP 1 LAST VALUE 348
J 0
(-4430 2275);
DISPLAY 0.617021 (-4430 2275);
PAINT SKYBLUE (-4430 2275);
FORCEPROP 1 LAST PART_NUMBER G21796-340
J 0
(-4435 2075);
DISPLAY 0.617021 (-4435 2075);
PAINT BLUE (-4435 2075);
FORCEPROP 1 LAST LOCATION R7D15
J 0
(-4430 2325);
DISPLAY 0.617021 (-4430 2325);
PAINT AQUA (-4430 2325);
FORCEPROP 2 LAST CDS_LIB mstr_discrete
J 0
(-4475 2200);
PAINT ORANGE (-4475 2200);
DISPLAY INVISIBLE (-4475 2200);
FORCEPROP 0 LAST ROOM PECI
J 0
(-4425 2425);
DISPLAY 1.021277 (-4425 2425);
PAINT ORANGE (-4425 2425);
DISPLAY INVISIBLE (-4425 2425);
FORCEPROP 1 LAST PATH I32
J 0
(-4425 2375);
DISPLAY 0.978723 (-4425 2375);
PAINT WHITE (-4425 2375);
DISPLAY INVISIBLE (-4425 2375);
FORCEPROP 2 LAST CDS_LOCATION R7D15
J 0
(-4430 2325);
DISPLAY 0.617021 (-4430 2325);
PAINT AQUA (-4430 2325);
DISPLAY INVISIBLE (-4430 2325);
FORCEPROP 2 LAST SEC 1
J 0
(-4425 2425);
DISPLAY 0.680851 (-4425 2425);
PAINT MONO (-4425 2425);
DISPLAY INVISIBLE (-4425 2425);
FORCEPROP 2 LAST SEC_TYPE 0402
J 0
(-4425 2425);
DISPLAY 1.021277 (-4425 2425);
PAINT ORANGE (-4425 2425);
DISPLAY INVISIBLE (-4425 2425);
FORCEPROP 0 LAST BOM_COST DEBUG
J 0
(-4425 2525);
DISPLAY 1.021277 (-4425 2525);
PAINT ORANGE (-4425 2525);
DISPLAY INVISIBLE (-4425 2525);
FORCEADD GND..1
(-4475 1950);
FORCEPROP 3 LASTPIN (-4475 2000) SIG_NAME GND\g
J 0
(-4465 2010);
DISPLAY 0.659574 (-4465 2010);
PAINT MONO (-4465 2010);
DISPLAY INVISIBLE (-4465 2010);
FORCEPROP 1 LAST PATH I33
J 0
(-4400 1950);
DISPLAY 0.872340 (-4400 1950);
PAINT AQUA (-4400 1950);
DISPLAY INVISIBLE (-4400 1950);
FORCEPROP 1 LAST BODY_TYPE PLUMBING
J 0
(-4520 1907);
DISPLAY 0.340426 (-4520 1907);
PAINT GREEN (-4520 1907);
DISPLAY INVISIBLE (-4520 1907);
FORCEPROP 1 LAST SIZE 1B
J 0
(-4400 1900);
DISPLAY 0.872340 (-4400 1900);
PAINT AQUA (-4400 1900);
DISPLAY INVISIBLE (-4400 1900);
FORCEPROP 2 LAST CDS_LIB mstr_symbols
J 0
(-4475 1950);
PAINT ORANGE (-4475 1950);
DISPLAY INVISIBLE (-4475 1950);
FORCEPROP 1 LAST VOLTAGE 0.0V
J 0
(-4520 1907);
DISPLAY 0.340426 (-4520 1907);
PAINT SKYBLUE (-4520 1907);
DISPLAY INVISIBLE (-4520 1907);
FORCEPROP 1 LAST HDL_POWER GND
J 0
(-4475 2100);
DISPLAY 0.872340 (-4475 2100);
PAINT GREEN (-4475 2100);
DISPLAY INVISIBLE (-4475 2100);
FORCEADD DESIGN_NOTE..1
(-5250 2325);
FORCEPROP 0 LAST L1 PD STUFFED IN PECI_PCH
J 0
(-5450 2225);
DISPLAY 0.617021 (-5450 2225);
PAINT WHITE (-5450 2225);
FORCEPROP 0 LAST L2 EMPTY FOR BMC SKU OR NM DEBUG
J 0
(-5450 2175);
DISPLAY 0.617021 (-5450 2175);
PAINT WHITE (-5450 2175);
FORCEPROP 1 LAST COMMENT_BODY TRUE
J 0
(-5225 2425);
DISPLAY 1.319149 (-5225 2425);
PAINT WHITE (-5225 2425);
DISPLAY INVISIBLE (-5225 2425);
FORCEPROP 2 LAST CDS_LIB mstr_symbols
J 0
(-5250 2325);
PAINT WHITE (-5250 2325);
DISPLAY INVISIBLE (-5250 2325);
FORCEADD DNS..2
(-4545 3120);
PAINT RED (-4545 3120);
FORCEPROP 1 LAST COMMENT_BODY TRUE
R 1
J 0
(-4470 2895);
DISPLAY 0.872340 (-4470 2895);
PAINT GREEN (-4470 2895);
DISPLAY INVISIBLE (-4470 2895);
FORCEPROP 2 LAST CDS_LIB mstr_misc
J 0
(-4545 3120);
PAINT ORANGE (-4545 3120);
DISPLAY INVISIBLE (-4545 3120);
FORCEADD DNS..2
(-4845 3495);
PAINT RED (-4845 3495);
FORCEPROP 1 LAST COMMENT_BODY TRUE
R 1
J 0
(-4770 3270);
DISPLAY 0.872340 (-4770 3270);
PAINT GREEN (-4770 3270);
DISPLAY INVISIBLE (-4770 3270);
FORCEPROP 2 LAST CDS_LIB mstr_misc
J 0
(-4845 3495);
PAINT ORANGE (-4845 3495);
DISPLAY INVISIBLE (-4845 3495);
FORCEADD CAD_NOTE..1
(-3675 3000);
FORCEPROP 0 LAST L2 PLACE ALL 3 STUFFING OPTION RESISTORS
J 0
(-3825 2850);
DISPLAY 0.617021 (-3825 2850);
PAINT WHITE (-3825 2850);
FORCEPROP 0 LAST L1 AS CLOSE AS POSSIBLE TO THE COMMON NODE
J 0
(-3825 2900);
DISPLAY 0.617021 (-3825 2900);
PAINT WHITE (-3825 2900);
FORCEPROP 0 LAST L3 SO THAT THE PECI BUS STUB IS AS SHORT AS
J 0
(-3825 2800);
DISPLAY 0.617021 (-3825 2800);
PAINT WHITE (-3825 2800);
FORCEPROP 0 LAST L4 POSSIBLE WHEN ANY OF THEM IS UNSTUFFED
J 0
(-3825 2750);
DISPLAY 0.617021 (-3825 2750);
PAINT WHITE (-3825 2750);
FORCEPROP 2 LAST CDS_LIB mstr_symbols
J 0
(-3675 3000);
PAINT WHITE (-3675 3000);
DISPLAY INVISIBLE (-3675 3000);
FORCEPROP 1 LAST COMMENT_BODY TRUE
J 0
(-3650 3100);
DISPLAY 1.319149 (-3650 3100);
PAINT WHITE (-3650 3100);
DISPLAY INVISIBLE (-3650 3100);
FORCEADD DESIGN_NOTE..1
(-5625 3625);
FORCEPROP 0 LAST L2 BMC PECI IS NOT USED
J 0
(-5825 3475);
DISPLAY 0.617021 (-5825 3475);
PAINT WHITE (-5825 3475);
FORCEPROP 0 LAST L1 PULL-UP FOR BMC IF
J 0
(-5825 3525);
DISPLAY 0.617021 (-5825 3525);
PAINT WHITE (-5825 3525);
FORCEPROP 1 LAST COMMENT_BODY TRUE
J 0
(-5600 3725);
DISPLAY 1.319149 (-5600 3725);
PAINT WHITE (-5600 3725);
DISPLAY INVISIBLE (-5600 3725);
FORCEPROP 2 LAST CDS_LIB mstr_symbols
J 0
(-5625 3625);
PAINT WHITE (-5625 3625);
DISPLAY INVISIBLE (-5625 3625);
FORCEADD INTEL_CORP_BPAGE..1
(0 0);
FORCEPROP 1 LAST CDS_CON_LAST_MODIFIED Tue Dec 01 11:52:11 2015
J 0
(-1425 325);
DISPLAY 1.361702 (-1425 325);
PAINT GREEN (-1425 325);
DISPLAY INVISIBLE (-1425 325);
FORCEPROP 1 LAST CUSTOM_TXT_CDS <CURRENT_DESIGN_SHEET> OF <TOTAL_DESIGN_SHEETS>
J 0
(-500 25);
PAINT GREEN (-500 25);
FORCEPROP 1 LAST CUSTOM_TXT_CDS <CON_LAST_MODIFIED>
J 0
(-1925 350);
PAINT GREEN (-1925 350);
FORCEPROP 2 LAST CUSTOM_TXT_CDS <XR_PAGE_TITLE>
J 0
(-7890 5250);
DISPLAY 0.638298 (-7890 5250);
PAINT PINK (-7890 5250);
DISPLAY INVISIBLE (-7890 5250);
FORCEPROP 1 LAST SCH_TITLE PECI
J 0
(-7950 50);
DISPLAY 1.212766 (-7950 50);
PAINT ORANGE (-7950 50);
FORCEPROP 1 LAST SCH_ADDRESS1 2200 Mission College Blvd.
J 0
(-3975 125);
DISPLAY 0.617021 (-3975 125);
PAINT GREEN (-3975 125);
FORCEPROP 1 LAST SCH_ADDRESS2 P.O. BOX 58119
J 0
(-3975 75);
DISPLAY 0.617021 (-3975 75);
PAINT GREEN (-3975 75);
FORCEPROP 1 LAST SCH_ADDRESS3 Santa Clara, CA 95052-8119
J 0
(-3975 25);
DISPLAY 0.617021 (-3975 25);
PAINT GREEN (-3975 25);
FORCEPROP 1 LAST SCH_NUMBER H4694802
J 0
(-1300 150);
DISPLAY 1.212766 (-1300 150);
PAINT YELLOW (-1300 150);
FORCEPROP 1 LAST SCH_DEPT BESD
J 1
(-4450 100);
DISPLAY 1.212766 (-4450 100);
PAINT YELLOW (-4450 100);
FORCEPROP 1 LAST SCH_REV 2.420
J 0
(-250 150);
DISPLAY 0.978723 (-250 150);
PAINT YELLOW (-250 150);
FORCEPROP 2 LAST PAGE_BORDER TRUE
J 0
(-7890 5250);
DISPLAY 0.851064 (-7890 5250);
PAINT PINK (-7890 5250);
DISPLAY INVISIBLE (-7890 5250);
FORCEPROP 2 LAST CDS_LIB mstr_symbols
J 0
(0 0);
DISPLAY 1.361702 (0 0);
PAINT ORANGE (0 0);
DISPLAY INVISIBLE (0 0);
FORCEPROP 1 LAST COMMENT_BODY TRUE
J 0
(12 12);
DISPLAY 0.617021 (12 12);
PAINT GREEN (12 12);
DISPLAY INVISIBLE (12 12);
FORCEPROP 2 LAST CDS_XR_PAGE_TITLE CR-166 : @BASEBOARD_FAB2_LIB.BASEBOARD_FAB2(SCH_1):PAGE166
J 0
(-7890 5250);
DISPLAY 0.638298 (-7890 5250);
PAINT PINK (-7890 5250);
DISPLAY INVISIBLE (-7890 5250);
WIRE 16 -1 (-5050 3600)(-5050 3650);
WIRE 16 -1 (-5050 3650)(-4850 3650);
WIRE 16 -1 (-4850 3725)(-4850 3650);
WIRE 16 -1 (-4850 3650)(-4850 3600);
WIRE 16 -1 (-4475 2000)(-4475 2100);
WIRE 16 -1 (-5700 1400)(-4050 1400);
FORCEPROP 2 LAST SIG_NAME PECI_CPU_G
J 0
(-5610 1410);
DISPLAY 0.617021 (-5610 1410);
PAINT ORANGE (-5610 1410);
WIRE 16 -1 (-4050 2525)(-4050 1400);
WIRE 16 -1 (-4050 3125)(-4050 2525);
WIRE 16 -1 (-4475 2525)(-4050 2525);
WIRE 16 -1 (-4575 2525)(-4475 2525);
WIRE 16 -1 (-4475 2300)(-4475 2525);
WIRE 16 -1 (-4450 3125)(-4050 3125);
WIRE 16 -1 (-4650 3125)(-5050 3125);
WIRE 16 -1 (-5050 3400)(-5050 3125);
WIRE 16 -1 (-5050 3125)(-5700 3125);
FORCEPROP 2 LAST SIG_NAME PECI_BMC
J 0
(-5630 3135);
DISPLAY 0.617021 (-5630 3135);
PAINT ORANGE (-5630 3135);
WIRE 16 -1 (-4775 2525)(-4850 2525);
WIRE 16 -1 (-4850 3400)(-4850 2525);
WIRE 16 -1 (-5700 2525)(-4850 2525);
FORCEPROP 2 LAST SIG_NAME PECI_PCH
J 0
(-5630 2535);
DISPLAY 0.617021 (-5630 2535);
PAINT ORANGE (-5630 2535);
DOT 1 (-4850 2525);
DOT 1 (-4475 2525);
DOT 1 (-5050 3125);
DOT 1 (-4850 3650);
DOT 1 (-4050 2525);
FORCENOTE
ROOM=SM_CONTROLLER
(-7841 336) 0;
DISPLAY LEFT (-7841 336);
DISPLAY 0.617021 (-7841 336);
PAINT PURPLE (-7841 336);
FORCENOTE
. 
(50 50) 0;
DISPLAY LEFT (50 50);
DISPLAY 0.617021 (50 50);
PAINT PURPLE (50 50);
QUIT
